# T6G (Grand Teton) — schematic netlist excerpt (pin names and nets, part order shuffled) for the footprints in the layout excerpt that follows; sources: Cadence DE-HDL packaged netlist, KiCad conversion of 04192023_DAF0TMB3IC0_F0TG_MB_C_brd_V02_OCP.brd

C6055  Q_CAP  0.01UF 50V 10% X7R  pkg C0402  page 177 : A = P1V2_AUX ; B = GND
C116  Q_CAP  0.1UF 25V 10% X7R  pkg 0402  page 93 : A = P3V3_AUX ; B = GND

(kicad_pcb
	(version 20260206)
	(generator "pcbnew")
	(generator_version "10.0")
	(general
		(thickness 1.6)
		(legacy_teardrops no)
	)
	(paper "A4")
	(title_block
		(title "04192023_DAF0TMB3IC0_F0TG_MB_C_brd_V02_OCP.brd")
		(comment 1 "Grand Teton / footprints 7311-7312 of 8354")
	)
	(layers
		(0 "F.Cu" signal "TOP")
		(4 "In1.Cu" signal "GND")
		(6 "In2.Cu" signal "IN1")
		(8 "In3.Cu" signal "GND1")
		(10 "In4.Cu" signal "IN2")
		(12 "In5.Cu" signal "GND2")
		(14 "In6.Cu" signal "IN3")
		(16 "In7.Cu" signal "GND3")
		(18 "In8.Cu" signal "VCC")
		(20 "In9.Cu" signal "VCC1")
		(22 "In10.Cu" signal "GND4")
		(24 "In11.Cu" signal "IN4")
		(26 "In12.Cu" signal "GND5")
		(28 "In13.Cu" signal "IN5")
		(30 "In14.Cu" signal "GND6")
		(32 "In15.Cu" signal "IN6")
		(34 "In16.Cu" signal "GND7")
		(2 "B.Cu" signal "BOTTOM")
		(9 "F.Adhes" user "F.Adhesive")
		(11 "B.Adhes" user "B.Adhesive")
		(13 "F.Paste" user "Package Geometry/Pastemask Top")
		(15 "B.Paste" user "Package Geometry/Pastemask Bottom")
		(5 "F.SilkS" user "Ref Des/Silkscreen Top")
		(7 "B.SilkS" user "Ref Des/Silkscreen Bottom")
		(1 "F.Mask" user "Board Geometry/Soldermask Top")
		(3 "B.Mask" user "Board Geometry/Soldermask Bottom")
		(17 "Dwgs.User" user "User.Drawings")
		(19 "Cmts.User" user "User.Comments")
		(21 "Eco1.User" user "User.Eco1")
		(23 "Eco2.User" user "User.Eco2")
		(25 "Edge.Cuts" user "Board Geometry/Outline")
		(27 "Margin" user)
		(31 "F.CrtYd" user "Package Geometry/Place Bound Top")
		(29 "B.CrtYd" user "Package Geometry/Place Bound Bottom")
		(35 "F.Fab" user "Ref Des/Assembly Top")
		(33 "B.Fab" user "Ref Des/Assembly Bottom")
	)
	(footprint ""
		(layer "B.Cu")
		(at 415.712402 -193.99631)
		(property "Reference" "C116"
			(at 0 0 0)
			(layer "B.SilkS")
			(hide yes)
			(effects
				(font
					(size 1.27 1.27)
				)
				(justify mirror)
			)
		)
		(property "Value" ""
			(at 0 0 0)
			(layer "B.Fab")
			(effects
				(font
					(size 1.27 1.27)
				)
				(justify mirror)
			)
		)
		(duplicate_pad_numbers_are_jumpers no)
		(fp_line
			(start -0.7874 -0.4064)
			(end -0.7874 0.4064)
			(stroke
				(width 0.1524)
				(type default)
			)
			(layer "B.SilkS")
		)
		(fp_line
			(start -0.7874 0.4064)
			(end 0.7874 0.4064)
			(stroke
				(width 0.1524)
				(type default)
			)
			(layer "B.SilkS")
		)
		(fp_line
			(start 0.7874 -0.4064)
			(end -0.7874 -0.4064)
			(stroke
				(width 0.1524)
				(type default)
			)
			(layer "B.SilkS")
		)
		(fp_line
			(start 0.7874 0.4064)
			(end 0.7874 -0.4064)
			(stroke
				(width 0.1524)
				(type default)
			)
			(layer "B.SilkS")
		)
		(fp_line
			(start -0.67945 -0.3048)
			(end -0.67945 0.3048)
			(stroke
				(width 0.1)
				(type default)
			)
			(layer "B.Fab")
		)
		(fp_line
			(start -0.67945 0.3048)
			(end -0.120396 0.3048)
			(stroke
				(width 0.1)
				(type default)
			)
			(layer "B.Fab")
		)
		(fp_line
			(start -0.12065 -0.3048)
			(end -0.67945 -0.3048)
			(stroke
				(width 0.1)
				(type default)
			)
			(layer "B.Fab")
		)
		(fp_line
			(start -0.12065 -0.2794)
			(end -0.12065 -0.3048)
			(stroke
				(width 0.1)
				(type default)
			)
			(layer "B.Fab")
		)
		(fp_line
			(start -0.120396 0.2794)
			(end 0.12065 0.2794)
			(stroke
				(width 0.1)
				(type default)
			)
			(layer "B.Fab")
		)
		(fp_line
			(start -0.120396 0.3048)
			(end -0.120396 0.2794)
			(stroke
				(width 0.1)
				(type default)
			)
			(layer "B.Fab")
		)
		(fp_line
			(start 0.12065 -0.305054)
			(end 0.12065 -0.2794)
			(stroke
				(width 0.1)
				(type default)
			)
			(layer "B.Fab")
		)
		(fp_line
			(start 0.12065 -0.2794)
			(end -0.12065 -0.2794)
			(stroke
				(width 0.1)
				(type default)
			)
			(layer "B.Fab")
		)
		(fp_line
			(start 0.12065 0.2794)
			(end 0.12065 0.3048)
			(stroke
				(width 0.1)
				(type default)
			)
			(layer "B.Fab")
		)
		(fp_line
			(start 0.12065 0.3048)
			(end 0.67945 0.3048)
			(stroke
				(width 0.1)
				(type default)
			)
			(layer "B.Fab")
		)
		(fp_line
			(start 0.67945 -0.305054)
			(end 0.12065 -0.305054)
			(stroke
				(width 0.1)
				(type default)
			)
			(layer "B.Fab")
		)
		(fp_line
			(start 0.67945 0.3048)
			(end 0.67945 -0.305054)
			(stroke
				(width 0.1)
				(type default)
			)
			(layer "B.Fab")
		)
		(pad "1" smd circle
			(at 0.40005 0 180)
			(size 0 0)
			(layers "B.Cu" "B.Mask" "B.Paste")
			(net "P3V3_AUX")
		)
		(pad "2" smd circle
			(at -0.40005 0 180)
			(size 0 0)
			(layers "B.Cu" "B.Mask" "B.Paste")
			(net "GND")
		)
	)
	(footprint ""
		(layer "B.Cu")
		(at 126.375668 -35.203892)
		(property "Reference" "C6055"
			(at 0 0 0)
			(layer "B.SilkS")
			(hide yes)
			(effects
				(font
					(size 1.27 1.27)
				)
				(justify mirror)
			)
		)
		(property "Value" ""
			(at 0 0 0)
			(layer "B.Fab")
			(effects
				(font
					(size 1.27 1.27)
				)
				(justify mirror)
			)
		)
		(duplicate_pad_numbers_are_jumpers no)
		(fp_line
			(start -0.7874 -0.4064)
			(end -0.7874 0.4064)
			(stroke
				(width 0.1524)
				(type default)
			)
			(layer "B.SilkS")
		)
		(fp_line
			(start -0.7874 0.4064)
			(end 0.7874 0.4064)
			(stroke
				(width 0.1524)
				(type default)
			)
			(layer "B.SilkS")
		)
		(fp_line
			(start 0.7874 -0.4064)
			(end -0.7874 -0.4064)
			(stroke
				(width 0.1524)
				(type default)
			)
			(layer "B.SilkS")
		)
		(fp_line
			(start 0.7874 0.4064)
			(end 0.7874 -0.4064)
			(stroke
				(width 0.1524)
				(type default)
			)
			(layer "B.SilkS")
		)
		(fp_line
			(start -0.67945 -0.3048)
			(end -0.67945 0.3048)
			(stroke
				(width 0.1)
				(type default)
			)
			(layer "B.Fab")
		)
		(fp_line
			(start -0.67945 0.3048)
			(end -0.120396 0.3048)
			(stroke
				(width 0.1)
				(type default)
			)
			(layer "B.Fab")
		)
		(fp_line
			(start -0.12065 -0.3048)
			(end -0.67945 -0.3048)
			(stroke
				(width 0.1)
				(type default)
			)
			(layer "B.Fab")
		)
		(fp_line
			(start -0.12065 -0.2794)
			(end -0.12065 -0.3048)
			(stroke
				(width 0.1)
				(type default)
			)
			(layer "B.Fab")
		)
		(fp_line
			(start -0.120396 0.2794)
			(end 0.12065 0.2794)
			(stroke
				(width 0.1)
				(type default)
			)
			(layer "B.Fab")
		)
		(fp_line
			(start -0.120396 0.3048)
			(end -0.120396 0.2794)
			(stroke
				(width 0.1)
				(type default)
			)
			(layer "B.Fab")
		)
		(fp_line
			(start 0.12065 -0.305054)
			(end 0.12065 -0.2794)
			(stroke
				(width 0.1)
				(type default)
			)
			(layer "B.Fab")
		)
		(fp_line
			(start 0.12065 -0.2794)
			(end -0.12065 -0.2794)
			(stroke
				(width 0.1)
				(type default)
			)
			(layer "B.Fab")
		)
		(fp_line
			(start 0.12065 0.2794)
			(end 0.12065 0.3048)
			(stroke
				(width 0.1)
				(type default)
			)
			(layer "B.Fab")
		)
		(fp_line
			(start 0.12065 0.3048)
			(end 0.67945 0.3048)
			(stroke
				(width 0.1)
				(type default)
			)
			(layer "B.Fab")
		)
		(fp_line
			(start 0.67945 -0.305054)
			(end 0.12065 -0.305054)
			(stroke
				(width 0.1)
				(type default)
			)
			(layer "B.Fab")
		)
		(fp_line
			(start 0.67945 0.3048)
			(end 0.67945 -0.305054)
			(stroke
				(width 0.1)
				(type default)
			)
			(layer "B.Fab")
		)
		(pad "1" smd circle
			(at 0.40005 0 180)
			(size 0 0)
			(layers "B.Cu" "B.Mask" "B.Paste")
			(net "P1V2_AUX")
		)
		(pad "2" smd circle
			(at -0.40005 0 180)
			(size 0 0)
			(layers "B.Cu" "B.Mask" "B.Paste")
			(net "GND")
		)
	)
)
